FILE_TYPE=LIBRARY_PARTS;
primitive 'SCONN67_NASA0S6730TS67';
  pin
    '2':
      PIN_NUMBER='(2)';
      BIDIRECTIONAL='TRUE';
      INPUT_LOAD='(-0.01,0.01)';
      OUTPUT_LOAD='(1.0,-1.0)';
    '4':
      PIN_NUMBER='(4)';
      BIDIRECTIONAL='TRUE';
      INPUT_LOAD='(-0.01,0.01)';
      OUTPUT_LOAD='(1.0,-1.0)';
    '6':
      PIN_NUMBER='(6)';
      BIDIRECTIONAL='TRUE';
      INPUT_LOAD='(-0.01,0.01)';
      OUTPUT_LOAD='(1.0,-1.0)';
    '16':
      PIN_NUMBER='(16)';
      BIDIRECTIONAL='TRUE';
      INPUT_LOAD='(-0.01,0.01)';
      OUTPUT_LOAD='(1.0,-1.0)';
    '18':
      PIN_NUMBER='(18)';
      BIDIRECTIONAL='TRUE';
      INPUT_LOAD='(-0.01,0.01)';
      OUTPUT_LOAD='(1.0,-1.0)';
    '20':
      PIN_NUMBER='(20)';
      BIDIRECTIONAL='TRUE';
      INPUT_LOAD='(-0.01,0.01)';
      OUTPUT_LOAD='(1.0,-1.0)';
    '22':
      PIN_NUMBER='(22)';
      BIDIRECTIONAL='TRUE';
      INPUT_LOAD='(-0.01,0.01)';
      OUTPUT_LOAD='(1.0,-1.0)';
    '24':
      PIN_NUMBER='(24)';
      BIDIRECTIONAL='TRUE';
      INPUT_LOAD='(-0.01,0.01)';
      OUTPUT_LOAD='(1.0,-1.0)';
    '26':
      PIN_NUMBER='(26)';
      BIDIRECTIONAL='TRUE';
      INPUT_LOAD='(-0.01,0.01)';
      OUTPUT_LOAD='(1.0,-1.0)';
    '28':
      PIN_NUMBER='(28)';
      BIDIRECTIONAL='TRUE';
      INPUT_LOAD='(-0.01,0.01)';
      OUTPUT_LOAD='(1.0,-1.0)';
    '30':
      PIN_NUMBER='(30)';
      BIDIRECTIONAL='TRUE';
      INPUT_LOAD='(-0.01,0.01)';
      OUTPUT_LOAD='(1.0,-1.0)';
    '32':
      PIN_NUMBER='(32)';
      BIDIRECTIONAL='TRUE';
      INPUT_LOAD='(-0.01,0.01)';
      OUTPUT_LOAD='(1.0,-1.0)';
    '34':
      PIN_NUMBER='(34)';
      BIDIRECTIONAL='TRUE';
      INPUT_LOAD='(-0.01,0.01)';
      OUTPUT_LOAD='(1.0,-1.0)';
    '36':
      PIN_NUMBER='(36)';
      BIDIRECTIONAL='TRUE';
      INPUT_LOAD='(-0.01,0.01)';
      OUTPUT_LOAD='(1.0,-1.0)';
    '38':
      PIN_NUMBER='(38)';
      BIDIRECTIONAL='TRUE';
      INPUT_LOAD='(-0.01,0.01)';
      OUTPUT_LOAD='(1.0,-1.0)';
    '40':
      PIN_NUMBER='(40)';
      BIDIRECTIONAL='TRUE';
      INPUT_LOAD='(-0.01,0.01)';
      OUTPUT_LOAD='(1.0,-1.0)';
    '42':
      PIN_NUMBER='(42)';
      BIDIRECTIONAL='TRUE';
      INPUT_LOAD='(-0.01,0.01)';
      OUTPUT_LOAD='(1.0,-1.0)';
    '44':
      PIN_NUMBER='(44)';
      BIDIRECTIONAL='TRUE';
      INPUT_LOAD='(-0.01,0.01)';
      OUTPUT_LOAD='(1.0,-1.0)';
    '46':
      PIN_NUMBER='(46)';
      BIDIRECTIONAL='TRUE';
      INPUT_LOAD='(-0.01,0.01)';
      OUTPUT_LOAD='(1.0,-1.0)';
    '48':
      PIN_NUMBER='(48)';
      BIDIRECTIONAL='TRUE';
      INPUT_LOAD='(-0.01,0.01)';
      OUTPUT_LOAD='(1.0,-1.0)';
    '50':
      PIN_NUMBER='(50)';
      BIDIRECTIONAL='TRUE';
      INPUT_LOAD='(-0.01,0.01)';
      OUTPUT_LOAD='(1.0,-1.0)';
    '52':
      PIN_NUMBER='(52)';
      BIDIRECTIONAL='TRUE';
      INPUT_LOAD='(-0.01,0.01)';
      OUTPUT_LOAD='(1.0,-1.0)';
    '54':
      PIN_NUMBER='(54)';
      BIDIRECTIONAL='TRUE';
      INPUT_LOAD='(-0.01,0.01)';
      OUTPUT_LOAD='(1.0,-1.0)';
    '56':
      PIN_NUMBER='(56)';
      BIDIRECTIONAL='TRUE';
      INPUT_LOAD='(-0.01,0.01)';
      OUTPUT_LOAD='(1.0,-1.0)';
    '58':
      PIN_NUMBER='(58)';
      BIDIRECTIONAL='TRUE';
      INPUT_LOAD='(-0.01,0.01)';
      OUTPUT_LOAD='(1.0,-1.0)';
    '60':
      PIN_NUMBER='(60)';
      BIDIRECTIONAL='TRUE';
      INPUT_LOAD='(-0.01,0.01)';
      OUTPUT_LOAD='(1.0,-1.0)';
    '62':
      PIN_NUMBER='(62)';
      BIDIRECTIONAL='TRUE';
      INPUT_LOAD='(-0.01,0.01)';
      OUTPUT_LOAD='(1.0,-1.0)';
    '64':
      PIN_NUMBER='(64)';
      BIDIRECTIONAL='TRUE';
      INPUT_LOAD='(-0.01,0.01)';
      OUTPUT_LOAD='(1.0,-1.0)';
    '66':
      PIN_NUMBER='(66)';
      BIDIRECTIONAL='TRUE';
      INPUT_LOAD='(-0.01,0.01)';
      OUTPUT_LOAD='(1.0,-1.0)';
    '68':
      PIN_NUMBER='(68)';
      BIDIRECTIONAL='TRUE';
      INPUT_LOAD='(-0.01,0.01)';
      OUTPUT_LOAD='(1.0,-1.0)';
    '70':
      PIN_NUMBER='(70)';
      BIDIRECTIONAL='TRUE';
      INPUT_LOAD='(-0.01,0.01)';
      OUTPUT_LOAD='(1.0,-1.0)';
    '72':
      PIN_NUMBER='(72)';
      BIDIRECTIONAL='TRUE';
      INPUT_LOAD='(-0.01,0.01)';
      OUTPUT_LOAD='(1.0,-1.0)';
    '74':
      PIN_NUMBER='(74)';
      BIDIRECTIONAL='TRUE';
      INPUT_LOAD='(-0.01,0.01)';
      OUTPUT_LOAD='(1.0,-1.0)';
    '1':
      PIN_NUMBER='(1)';
      BIDIRECTIONAL='TRUE';
      INPUT_LOAD='(-0.01,0.01)';
      OUTPUT_LOAD='(1.0,-1.0)';
    '3':
      PIN_NUMBER='(3)';
      BIDIRECTIONAL='TRUE';
      INPUT_LOAD='(-0.01,0.01)';
      OUTPUT_LOAD='(1.0,-1.0)';
    '5':
      PIN_NUMBER='(5)';
      BIDIRECTIONAL='TRUE';
      INPUT_LOAD='(-0.01,0.01)';
      OUTPUT_LOAD='(1.0,-1.0)';
    '7':
      PIN_NUMBER='(7)';
      BIDIRECTIONAL='TRUE';
      INPUT_LOAD='(-0.01,0.01)';
      OUTPUT_LOAD='(1.0,-1.0)';
    '17':
      PIN_NUMBER='(17)';
      BIDIRECTIONAL='TRUE';
      INPUT_LOAD='(-0.01,0.01)';
      OUTPUT_LOAD='(1.0,-1.0)';
    '19':
      PIN_NUMBER='(19)';
      BIDIRECTIONAL='TRUE';
      INPUT_LOAD='(-0.01,0.01)';
      OUTPUT_LOAD='(1.0,-1.0)';
    '21':
      PIN_NUMBER='(21)';
      BIDIRECTIONAL='TRUE';
      INPUT_LOAD='(-0.01,0.01)';
      OUTPUT_LOAD='(1.0,-1.0)';
    '23':
      PIN_NUMBER='(23)';
      BIDIRECTIONAL='TRUE';
      INPUT_LOAD='(-0.01,0.01)';
      OUTPUT_LOAD='(1.0,-1.0)';
    '25':
      PIN_NUMBER='(25)';
      BIDIRECTIONAL='TRUE';
      INPUT_LOAD='(-0.01,0.01)';
      OUTPUT_LOAD='(1.0,-1.0)';
    '27':
      PIN_NUMBER='(27)';
      BIDIRECTIONAL='TRUE';
      INPUT_LOAD='(-0.01,0.01)';
      OUTPUT_LOAD='(1.0,-1.0)';
    '29':
      PIN_NUMBER='(29)';
      BIDIRECTIONAL='TRUE';
      INPUT_LOAD='(-0.01,0.01)';
      OUTPUT_LOAD='(1.0,-1.0)';
    '31':
      PIN_NUMBER='(31)';
      BIDIRECTIONAL='TRUE';
      INPUT_LOAD='(-0.01,0.01)';
      OUTPUT_LOAD='(1.0,-1.0)';
    '33':
      PIN_NUMBER='(33)';
      BIDIRECTIONAL='TRUE';
      INPUT_LOAD='(-0.01,0.01)';
      OUTPUT_LOAD='(1.0,-1.0)';
    '35':
      PIN_NUMBER='(35)';
      BIDIRECTIONAL='TRUE';
      INPUT_LOAD='(-0.01,0.01)';
      OUTPUT_LOAD='(1.0,-1.0)';
    '37':
      PIN_NUMBER='(37)';
      BIDIRECTIONAL='TRUE';
      INPUT_LOAD='(-0.01,0.01)';
      OUTPUT_LOAD='(1.0,-1.0)';
    '39':
      PIN_NUMBER='(39)';
      BIDIRECTIONAL='TRUE';
      INPUT_LOAD='(-0.01,0.01)';
      OUTPUT_LOAD='(1.0,-1.0)';
    '41':
      PIN_NUMBER='(41)';
      BIDIRECTIONAL='TRUE';
      INPUT_LOAD='(-0.01,0.01)';
      OUTPUT_LOAD='(1.0,-1.0)';
    '43':
      PIN_NUMBER='(43)';
      BIDIRECTIONAL='TRUE';
      INPUT_LOAD='(-0.01,0.01)';
      OUTPUT_LOAD='(1.0,-1.0)';
    '45':
      PIN_NUMBER='(45)';
      BIDIRECTIONAL='TRUE';
      INPUT_LOAD='(-0.01,0.01)';
      OUTPUT_LOAD='(1.0,-1.0)';
    '47':
      PIN_NUMBER='(47)';
      BIDIRECTIONAL='TRUE';
      INPUT_LOAD='(-0.01,0.01)';
      OUTPUT_LOAD='(1.0,-1.0)';
    '49':
      PIN_NUMBER='(49)';
      BIDIRECTIONAL='TRUE';
      INPUT_LOAD='(-0.01,0.01)';
      OUTPUT_LOAD='(1.0,-1.0)';
    '51':
      PIN_NUMBER='(51)';
      BIDIRECTIONAL='TRUE';
      INPUT_LOAD='(-0.01,0.01)';
      OUTPUT_LOAD='(1.0,-1.0)';
    '53':
      PIN_NUMBER='(53)';
      BIDIRECTIONAL='TRUE';
      INPUT_LOAD='(-0.01,0.01)';
      OUTPUT_LOAD='(1.0,-1.0)';
    '55':
      PIN_NUMBER='(55)';
      BIDIRECTIONAL='TRUE';
      INPUT_LOAD='(-0.01,0.01)';
      OUTPUT_LOAD='(1.0,-1.0)';
    '57':
      PIN_NUMBER='(57)';
      BIDIRECTIONAL='TRUE';
      INPUT_LOAD='(-0.01,0.01)';
      OUTPUT_LOAD='(1.0,-1.0)';
    '59':
      PIN_NUMBER='(59)';
      BIDIRECTIONAL='TRUE';
      INPUT_LOAD='(-0.01,0.01)';
      OUTPUT_LOAD='(1.0,-1.0)';
    '61':
      PIN_NUMBER='(61)';
      BIDIRECTIONAL='TRUE';
      INPUT_LOAD='(-0.01,0.01)';
      OUTPUT_LOAD='(1.0,-1.0)';
    '63':
      PIN_NUMBER='(63)';
      BIDIRECTIONAL='TRUE';
      INPUT_LOAD='(-0.01,0.01)';
      OUTPUT_LOAD='(1.0,-1.0)';
    '65':
      PIN_NUMBER='(65)';
      BIDIRECTIONAL='TRUE';
      INPUT_LOAD='(-0.01,0.01)';
      OUTPUT_LOAD='(1.0,-1.0)';
    '67':
      PIN_NUMBER='(67)';
      BIDIRECTIONAL='TRUE';
      INPUT_LOAD='(-0.01,0.01)';
      OUTPUT_LOAD='(1.0,-1.0)';
    '69':
      PIN_NUMBER='(69)';
      BIDIRECTIONAL='TRUE';
      INPUT_LOAD='(-0.01,0.01)';
      OUTPUT_LOAD='(1.0,-1.0)';
    '71':
      PIN_NUMBER='(71)';
      BIDIRECTIONAL='TRUE';
      INPUT_LOAD='(-0.01,0.01)';
      OUTPUT_LOAD='(1.0,-1.0)';
    '73':
      PIN_NUMBER='(73)';
      BIDIRECTIONAL='TRUE';
      INPUT_LOAD='(-0.01,0.01)';
      OUTPUT_LOAD='(1.0,-1.0)';
    '75':
      PIN_NUMBER='(75)';
      BIDIRECTIONAL='TRUE';
      INPUT_LOAD='(-0.01,0.01)';
      OUTPUT_LOAD='(1.0,-1.0)';
    'G1':
      PIN_NUMBER='(G1)';
      PINUSE='POWER';
      NO_LOAD_CHECK='Both';
      NO_IO_CHECK='Both';
      NO_ASSERT_CHECK='TRUE';
      NO_DIR_CHECK='TRUE';
      ALLOW_CONNECT='TRUE';
    'G2':
      PIN_NUMBER='(G2)';
      PINUSE='POWER';
      NO_LOAD_CHECK='Both';
      NO_IO_CHECK='Both';
      NO_ASSERT_CHECK='TRUE';
      NO_DIR_CHECK='TRUE';
      ALLOW_CONNECT='TRUE';
  end_pin;
  body
    PART_NAME='SCONN67_NASA0S6730TS67';
    BODY_NAME='SCONN67_NASA0S6730TS67';
    PHYS_DES_PREFIX='J';
    CLASS='IO';
    NC_PINS='(H1,H2)';
  end_body;
end_primitive;

END.
